(kicad_pcb
	(version 20241229)
	(generator "pcbnew")
	(generator_version "9.0")
	(general
		(thickness 1.62)
		(legacy_teardrops no)
	)
	(paper "A3")
	(title_block
		(title "COM Express 7 Baseboard")
		(date "2025-02-04")
		(rev "1.1.2")
		(company "Antmicro Ltd")
		(comment 1 "www.antmicro.com")
		(comment 9 "footprints 281-285 of 802")
	)
	(layers
		(0 "F.Cu" signal)
		(4 "In1.Cu" signal)
		(6 "In2.Cu" signal)
		(8 "In3.Cu" signal)
		(10 "In4.Cu" signal)
		(12 "In5.Cu" signal)
		(14 "In6.Cu" signal)
		(2 "B.Cu" signal)
		(9 "F.Adhes" user "F.Adhesive")
		(11 "B.Adhes" user "B.Adhesive")
		(13 "F.Paste" user)
		(15 "B.Paste" user)
		(5 "F.SilkS" user "F.Silkscreen")
		(7 "B.SilkS" user "B.Silkscreen")
		(1 "F.Mask" user)
		(3 "B.Mask" user)
		(17 "Dwgs.User" user "User.Drawings")
		(19 "Cmts.User" user "User.Comments")
		(21 "Eco1.User" user "User.Eco1")
		(23 "Eco2.User" user "User.Eco2")
		(25 "Edge.Cuts" user)
		(27 "Margin" user)
		(31 "F.CrtYd" user "F.Courtyard")
		(29 "B.CrtYd" user "B.Courtyard")
		(35 "F.Fab" user)
		(33 "B.Fab" user)
	)
	(footprint "antmicro-footprints:SOT-563"
		(layer "F.Cu")
		(at 312.4005 95.1365 -90)
		(property "Reference" "U21"
			(at -3.6265 -3.5995 180)
			(layer "F.SilkS")
			(effects
				(font
					(size 0.7 0.7)
					(thickness 0.15)
				)
				(justify right bottom)
			)
		)
		(property "Value" "TPS564247DRLR"
			(at 0 2.000001 90)
			(layer "F.Fab")
			(effects
				(font
					(size 0.7 0.7)
					(thickness 0.15)
				)
				(justify right bottom)
			)
		)
		(property "Datasheet" "https://www.ti.com/lit/ds/symlink/tps564247.pdf?ts=1713526387938&ref_url=https%253A%252F%252Fwww.mouser.pl%252F"
			(at 0 0 270)
			(layer "F.Fab")
			(hide yes)
			(effects
				(font
					(size 1.27 1.27)
					(thickness 0.15)
				)
			)
		)
		(property "Author" "Antmicro"
			(at 217.264 407.537 0)
			(layer "F.Fab")
			(hide yes)
			(effects
				(font
					(size 1 1)
					(thickness 0.15)
				)
			)
		)
		(property "License" "Apache-2.0"
			(at 217.264 407.537 0)
			(layer "F.Fab")
			(hide yes)
			(effects
				(font
					(size 1 1)
					(thickness 0.15)
				)
			)
		)
		(property "MPN" "TPS564247DRLR"
			(at 217.264 407.537 0)
			(layer "F.Fab")
			(hide yes)
			(effects
				(font
					(size 1 1)
					(thickness 0.15)
				)
			)
		)
		(property "Manufacturer" "Texas Instruments"
			(at 217.264 407.537 0)
			(layer "F.Fab")
			(hide yes)
			(effects
				(font
					(size 1 1)
					(thickness 0.15)
				)
			)
		)
		(sheetname "Power")
		(sheetfile "power.kicad_sch")
		(attr smd)
		(fp_line
			(start 0.776 0.972)
			(end 0.526 0.972)
			(stroke
				(width 0.15)
				(type solid)
			)
			(layer "F.SilkS")
		)
		(fp_line
			(start -0.778 0.949)
			(end -0.424 0.949)
			(stroke
				(width 0.15)
				(type solid)
			)
			(layer "F.SilkS")
		)
		(fp_line
			(start -0.778 0.776)
			(end -0.778 0.949)
			(stroke
				(width 0.15)
				(type solid)
			)
			(layer "F.SilkS")
		)
		(fp_line
			(start 0.776 0.776)
			(end 0.776 0.972)
			(stroke
				(width 0.15)
				(type solid)
			)
			(layer "F.SilkS")
		)
		(fp_line
			(start -0.499 -0.974)
			(end -0.724 -0.778)
			(stroke
				(width 0.15)
				(type solid)
			)
			(layer "F.SilkS")
		)
		(fp_line
			(start 0.776 -0.974)
			(end 0.776 -0.778)
			(stroke
				(width 0.15)
				(type solid)
			)
			(layer "F.SilkS")
		)
		(fp_line
			(start 0.776 -0.974)
			(end 0.526 -0.974)
			(stroke
				(width 0.15)
				(type solid)
			)
			(layer "F.SilkS")
		)
		(fp_circle
			(center -0.903 -0.999)
			(end -0.952 -0.95)
			(stroke
				(width 0.15)
				(type solid)
			)
			(fill yes)
			(layer "F.SilkS")
		)
		(fp_rect
			(start 1.19 -1.12)
			(end -1.2 1.1)
			(stroke
				(width 0.05)
				(type solid)
			)
			(fill no)
			(layer "F.CrtYd")
		)
		(fp_line
			(start 0.651 0.847)
			(end -0.653 0.847)
			(stroke
				(width 0.15)
				(type solid)
			)
			(layer "F.Fab")
		)
		(fp_line
			(start -0.653 -0.678)
			(end -0.653 0.847)
			(stroke
				(width 0.15)
				(type solid)
			)
			(layer "F.Fab")
		)
		(fp_line
			(start -0.453 -0.849)
			(end -0.653 -0.678)
			(stroke
				(width 0.15)
				(type solid)
			)
			(layer "F.Fab")
		)
		(fp_line
			(start -0.453 -0.849)
			(end 0.651 -0.849)
			(stroke
				(width 0.15)
				(type solid)
			)
			(layer "F.Fab")
		)
		(fp_line
			(start 0.651 -0.849)
			(end 0.651 0.847)
			(stroke
				(width 0.15)
				(type solid)
			)
			(layer "F.Fab")
		)
		(pad "1" smd roundrect
			(at -0.749 -0.499 180)
			(size 0.3 0.6)
			(layers "F.Cu" "F.Mask" "F.Paste")
			(roundrect_rratio 0.25)
			(net 62 "+12V_AON")
			(pinfunction "V_{IN}")
			(pintype "power_in")
			(teardrops
				(best_length_ratio 0.2)
				(max_length 1)
				(best_width_ratio 0.9)
				(max_width 2)
				(curved_edges yes)
				(filter_ratio 0.9)
				(enabled yes)
				(allow_two_segments yes)
				(prefer_zone_connections yes)
			)
		)
		(pad "2" smd roundrect
			(at -0.749 0.001 180)
			(size 0.3 0.6)
			(layers "F.Cu" "F.Mask" "F.Paste")
			(roundrect_rratio 0.25)
			(net 870 "Net-(U21-SW)")
			(pinfunction "SW")
			(pintype "passive")
			(teardrops
				(best_length_ratio 0.2)
				(max_length 1)
				(best_width_ratio 0.9)
				(max_width 2)
				(curved_edges yes)
				(filter_ratio 0.9)
				(enabled yes)
				(allow_two_segments yes)
				(prefer_zone_connections yes)
			)
		)
		(pad "3" smd roundrect
			(at -0.749 0.497 180)
			(size 0.3 0.6)
			(layers "F.Cu" "F.Mask" "F.Paste")
			(roundrect_rratio 0.25)
			(net 1 "GND")
			(pinfunction "GND")
			(pintype "power_in")
			(teardrops
				(best_length_ratio 0.2)
				(max_length 1)
				(best_width_ratio 0.9)
				(max_width 2)
				(curved_edges yes)
				(filter_ratio 0.9)
				(enabled yes)
				(allow_two_segments yes)
				(prefer_zone_connections yes)
			)
		)
		(pad "4" smd roundrect
			(at 0.747 0.497 180)
			(size 0.3 0.6)
			(layers "F.Cu" "F.Mask" "F.Paste")
			(roundrect_rratio 0.25)
			(net 1 "GND")
			(pinfunction "AGND")
			(pintype "power_in")
			(teardrops
				(best_length_ratio 0.2)
				(max_length 1)
				(best_width_ratio 0.9)
				(max_width 2)
				(curved_edges yes)
				(filter_ratio 0.9)
				(enabled yes)
				(allow_two_segments yes)
				(prefer_zone_connections yes)
			)
		)
		(pad "5" smd roundrect
			(at 0.747 0.001 180)
			(size 0.3 0.6)
			(layers "F.Cu" "F.Mask" "F.Paste")
			(roundrect_rratio 0.25)
			(net 584 "Net-(U21-EN)")
			(pinfunction "EN")
			(pintype "passive")
			(teardrops
				(best_length_ratio 0.2)
				(max_length 1)
				(best_width_ratio 0.9)
				(max_width 2)
				(curved_edges yes)
				(filter_ratio 0.9)
				(enabled yes)
				(allow_two_segments yes)
				(prefer_zone_connections yes)
			)
		)
		(pad "6" smd roundrect
			(at 0.747 -0.499 180)
			(size 0.3 0.6)
			(layers "F.Cu" "F.Mask" "F.Paste")
			(roundrect_rratio 0.25)
			(net 585 "Net-(U21-FB)")
			(pinfunction "FB")
			(pintype "passive")
			(teardrops
				(best_length_ratio 0.2)
				(max_length 1)
				(best_width_ratio 0.9)
				(max_width 2)
				(curved_edges yes)
				(filter_ratio 0.9)
				(enabled yes)
				(allow_two_segments yes)
				(prefer_zone_connections yes)
			)
		)
	)
	(footprint "antmicro-footprints:C_0402_1005Metric"
		(layer "F.Cu")
		(at 129.5 99.49 -90)
		(descr "Capacitor SMD 0402")
		(tags "capacitor SMD 0402")
		(property "Reference" "C15"
			(at -1.13 0.5 90)
			(layer "F.SilkS")
			(effects
				(font
					(size 0.7 0.7)
					(thickness 0.15)
				)
				(justify right bottom)
			)
		)
		(property "Value" "C_100n_0402"
			(at -1.022927 2.155213 90)
			(layer "F.Fab")
			(effects
				(font
					(size 0.7 0.7)
					(thickness 0.15)
				)
				(justify right bottom)
			)
		)
		(property "Datasheet" "https://www.murata.com/products/productdetail?partno=GRM155R61H104KE14%23"
			(at 0 0 270)
			(layer "F.Fab")
			(hide yes)
			(effects
				(font
					(size 1.27 1.27)
					(thickness 0.15)
				)
			)
		)
		(property "Author" "Antmicro"
			(at 30.01 228.99 0)
			(layer "F.Fab")
			(hide yes)
			(effects
				(font
					(size 1 1)
					(thickness 0.15)
				)
			)
		)
		(property "Dielectric" "X5R"
			(at 30.01 228.99 0)
			(layer "F.Fab")
			(hide yes)
			(effects
				(font
					(size 1 1)
					(thickness 0.15)
				)
			)
		)
		(property "License" "Apache-2.0"
			(at 30.01 228.99 0)
			(layer "F.Fab")
			(hide yes)
			(effects
				(font
					(size 1 1)
					(thickness 0.15)
				)
			)
		)
		(property "MPN" "GRM155R61H104KE14D"
			(at 30.01 228.99 0)
			(layer "F.Fab")
			(hide yes)
			(effects
				(font
					(size 1 1)
					(thickness 0.15)
				)
			)
		)
		(property "Manufacturer" "Murata"
			(at 30.01 228.99 0)
			(layer "F.Fab")
			(hide yes)
			(effects
				(font
					(size 1 1)
					(thickness 0.15)
				)
			)
		)
		(property "Public" "False"
			(at 30.01 228.99 0)
			(layer "F.Fab")
			(hide yes)
			(effects
				(font
					(size 1 1)
					(thickness 0.15)
				)
			)
		)
		(property "Val" "100n"
			(at 30.01 228.99 0)
			(layer "F.Fab")
			(hide yes)
			(effects
				(font
					(size 1 1)
					(thickness 0.15)
				)
			)
		)
		(property "Voltage" "50V"
			(at 30.01 228.99 0)
			(layer "F.Fab")
			(hide yes)
			(effects
				(font
					(size 1 1)
					(thickness 0.15)
				)
			)
		)
		(sheetname "2xUSB3.0+RJ45")
		(sheetfile "usb3+rj45.kicad_sch")
		(attr smd)
		(fp_rect
			(start -0.925 -0.47)
			(end 0.925 0.47)
			(stroke
				(width 0.05)
				(type default)
			)
			(fill no)
			(layer "F.CrtYd")
		)
		(fp_line
			(start -0.494 0.248)
			(end -0.494 -0.25)
			(stroke
				(width 0.15)
				(type solid)
			)
			(layer "F.Fab")
		)
		(fp_line
			(start 0.504 0.248)
			(end -0.494 0.248)
			(stroke
				(width 0.15)
				(type solid)
			)
			(layer "F.Fab")
		)
		(fp_line
			(start -0.494 -0.25)
			(end 0.504 -0.25)
			(stroke
				(width 0.15)
				(type solid)
			)
			(layer "F.Fab")
		)
		(fp_line
			(start 0.504 -0.25)
			(end 0.504 0.248)
			(stroke
				(width 0.15)
				(type solid)
			)
			(layer "F.Fab")
		)
		(pad "1" smd roundrect
			(at -0.48 0 270)
			(size 0.59 0.64)
			(layers "F.Cu" "F.Mask" "F.Paste")
			(roundrect_rratio 0.25)
			(net 51 "Net-(C13-Pad1)")
			(pintype "passive")
			(teardrops
				(best_length_ratio 0.2)
				(max_length 1)
				(best_width_ratio 0.9)
				(max_width 2)
				(curved_edges yes)
				(filter_ratio 0.9)
				(enabled yes)
				(allow_two_segments yes)
				(prefer_zone_connections yes)
			)
		)
		(pad "2" smd roundrect
			(at 0.48 0 270)
			(size 0.59 0.64)
			(layers "F.Cu" "F.Mask" "F.Paste")
			(roundrect_rratio 0.25)
			(net 1 "GND")
			(pintype "passive")
			(teardrops
				(best_length_ratio 0.2)
				(max_length 1)
				(best_width_ratio 0.9)
				(max_width 2)
				(curved_edges yes)
				(filter_ratio 0.9)
				(enabled yes)
				(allow_two_segments yes)
				(prefer_zone_connections yes)
			)
		)
	)
	(footprint "antmicro-footprints:R_0402_1005Metric"
		(layer "F.Cu")
		(at 112.9 145.86 180)
		(descr "Resistor SMD 0402")
		(tags "resistor SMD 0402")
		(property "Reference" "R203"
			(at 0.85 -0.45 0)
			(layer "F.SilkS")
			(effects
				(font
					(size 0.7 0.7)
					(thickness 0.15)
				)
				(justify right bottom)
			)
		)
		(property "Value" "R_1k_0402"
			(at -1.011843 1.772047 0)
			(layer "F.Fab")
			(effects
				(font
					(size 0.7 0.7)
					(thickness 0.15)
				)
				(justify right bottom)
			)
		)
		(property "Datasheet" "https://www.bourns.com/docs/product-datasheets/cr.pdf"
			(at 0 0 180)
			(layer "F.Fab")
			(hide yes)
			(effects
				(font
					(size 1.27 1.27)
					(thickness 0.15)
				)
			)
		)
		(property "Author" "Antmicro"
			(at 225.8 291.72 0)
			(layer "F.Fab")
			(hide yes)
			(effects
				(font
					(size 1 1)
					(thickness 0.15)
				)
			)
		)
		(property "License" "Apache-2.0"
			(at 225.8 291.72 0)
			(layer "F.Fab")
			(hide yes)
			(effects
				(font
					(size 1 1)
					(thickness 0.15)
				)
			)
		)
		(property "MPN" "CR0402-FX-1001GLF"
			(at 225.8 291.72 0)
			(layer "F.Fab")
			(hide yes)
			(effects
				(font
					(size 1 1)
					(thickness 0.15)
				)
			)
		)
		(property "Manufacturer" "Bourns"
			(at 225.8 291.72 0)
			(layer "F.Fab")
			(hide yes)
			(effects
				(font
					(size 1 1)
					(thickness 0.15)
				)
			)
		)
		(property "Public" "False"
			(at 225.8 291.72 0)
			(layer "F.Fab")
			(hide yes)
			(effects
				(font
					(size 1 1)
					(thickness 0.15)
				)
			)
		)
		(property "Tolerance" "1%"
			(at 225.8 291.72 0)
			(layer "F.Fab")
			(hide yes)
			(effects
				(font
					(size 1 1)
					(thickness 0.15)
				)
			)
		)
		(property "Val" "1k"
			(at 225.8 291.72 0)
			(layer "F.Fab")
			(hide yes)
			(effects
				(font
					(size 1 1)
					(thickness 0.15)
				)
			)
		)
		(sheetname "PCIe redriver")
		(sheetfile "pcie_redriver.kicad_sch")
		(attr smd dnp)
		(fp_rect
			(start -0.925 -0.47)
			(end 0.925 0.47)
			(stroke
				(width 0.05)
				(type default)
			)
			(fill no)
			(layer "F.CrtYd")
		)
		(fp_rect
			(start -0.5 -0.25)
			(end 0.5 0.25)
			(stroke
				(width 0.15)
				(type solid)
			)
			(fill no)
			(layer "F.Fab")
		)
		(pad "1" smd roundrect
			(at -0.48 0 180)
			(size 0.59 0.64)
			(layers "F.Cu" "F.Mask" "F.Paste")
			(roundrect_rratio 0.25)
			(net 1 "GND")
			(pintype "passive")
			(teardrops
				(best_length_ratio 0.2)
				(max_length 1)
				(best_width_ratio 0.9)
				(max_width 2)
				(curved_edges yes)
				(filter_ratio 0.9)
				(enabled yes)
				(allow_two_segments yes)
				(prefer_zone_connections yes)
			)
		)
		(pad "2" smd roundrect
			(at 0.48 0 180)
			(size 0.59 0.64)
			(layers "F.Cu" "F.Mask" "F.Paste")
			(roundrect_rratio 0.25)
			(net 623 "/PCIe redriver/TX_EQ0")
			(pintype "passive")
			(teardrops
				(best_length_ratio 0.2)
				(max_length 1)
				(best_width_ratio 0.9)
				(max_width 2)
				(curved_edges yes)
				(filter_ratio 0.9)
				(enabled yes)
				(allow_two_segments yes)
				(prefer_zone_connections yes)
			)
		)
	)
	(footprint "antmicro-footprints:C_0603_1608Metric"
		(layer "F.Cu")
		(at 314.275499 134.21 90)
		(descr "Capacitor SMD 0603")
		(tags "capacitor 0603")
		(property "Reference" "C61"
			(at 1.15 0.674501 90)
			(layer "F.SilkS")
			(effects
				(font
					(size 0.7 0.7)
					(thickness 0.15)
				)
				(justify left bottom)
			)
		)
		(property "Value" "C_22u_16V_0603"
			(at -1.42757 1.770288 90)
			(layer "F.Fab")
			(effects
				(font
					(size 0.7 0.7)
					(thickness 0.15)
				)
				(justify left bottom)
			)
		)
		(property "Datasheet" "https://product.samsungsem.com/mlcc/CL10A226MO7JZN.do"
			(at 0 0 90)
			(layer "F.Fab")
			(hide yes)
			(effects
				(font
					(size 1.27 1.27)
					(thickness 0.15)
				)
			)
		)
		(property "Author" "Antmicro"
			(at 448.485499 -180.065499 0)
			(layer "F.Fab")
			(hide yes)
			(effects
				(font
					(size 1 1)
					(thickness 0.15)
				)
			)
		)
		(property "Dielectric" ""
			(at 448.485499 -180.065499 0)
			(layer "F.Fab")
			(hide yes)
			(effects
				(font
					(size 1 1)
					(thickness 0.15)
				)
			)
		)
		(property "License" "Apache-2.0"
			(at 448.485499 -180.065499 0)
			(layer "F.Fab")
			(hide yes)
			(effects
				(font
					(size 1 1)
					(thickness 0.15)
				)
			)
		)
		(property "MPN" "CL10A226MO7JZNC"
			(at 448.485499 -180.065499 0)
			(layer "F.Fab")
			(hide yes)
			(effects
				(font
					(size 1 1)
					(thickness 0.15)
				)
			)
		)
		(property "Manufacturer" "Samsung Electro-Mechanics"
			(at 448.485499 -180.065499 0)
			(layer "F.Fab")
			(hide yes)
			(effects
				(font
					(size 1 1)
					(thickness 0.15)
				)
			)
		)
		(property "Public" "False"
			(at 448.485499 -180.065499 0)
			(layer "F.Fab")
			(hide yes)
			(effects
				(font
					(size 1 1)
					(thickness 0.15)
				)
			)
		)
		(property "Val" "22u"
			(at 448.485499 -180.065499 0)
			(layer "F.Fab")
			(hide yes)
			(effects
				(font
					(size 1 1)
					(thickness 0.15)
				)
			)
		)
		(property "Voltage" "16V"
			(at 448.485499 -180.065499 0)
			(layer "F.Fab")
			(hide yes)
			(effects
				(font
					(size 1 1)
					(thickness 0.15)
				)
			)
		)
		(sheetname "Power")
		(sheetfile "power.kicad_sch")
		(attr smd)
		(fp_line
			(start -0.15 -0.4)
			(end 0.15 -0.4)
			(stroke
				(width 0.15)
				(type solid)
			)
			(layer "F.SilkS")
		)
		(fp_line
			(start -0.15 0.4)
			(end 0.15 0.4)
			(stroke
				(width 0.15)
				(type solid)
			)
			(layer "F.SilkS")
		)
		(fp_rect
			(start -1.25 -0.65)
			(end 1.25 0.65)
			(stroke
				(width 0.05)
				(type solid)
			)
			(fill no)
			(layer "F.CrtYd")
		)
		(fp_rect
			(start -0.8 -0.4)
			(end 0.8 0.4)
			(stroke
				(width 0.15)
				(type solid)
			)
			(fill no)
			(layer "F.Fab")
		)
		(pad "1" smd roundrect
			(at -0.7 0 90)
			(size 0.8 1)
			(layers "F.Cu" "F.Mask" "F.Paste")
			(roundrect_rratio 0.2)
			(net 1 "GND")
			(pintype "passive")
			(teardrops
				(best_length_ratio 0.2)
				(max_length 1)
				(best_width_ratio 0.9)
				(max_width 2)
				(curved_edges yes)
				(filter_ratio 0.9)
				(enabled yes)
				(allow_two_segments yes)
				(prefer_zone_connections yes)
			)
		)
		(pad "2" smd roundrect
			(at 0.7 0 90)
			(size 0.8 1)
			(layers "F.Cu" "F.Mask" "F.Paste")
			(roundrect_rratio 0.2)
			(net 62 "+12V_AON")
			(pintype "passive")
			(teardrops
				(best_length_ratio 0.2)
				(max_length 1)
				(best_width_ratio 0.9)
				(max_width 2)
				(curved_edges yes)
				(filter_ratio 0.9)
				(enabled yes)
				(allow_two_segments yes)
				(prefer_zone_connections yes)
			)
		)
	)
	(footprint "antmicro-footprints:R_0402_1005Metric"
		(layer "F.Cu")
		(at 130.15 89.51 -90)
		(descr "Resistor SMD 0402")
		(tags "resistor SMD 0402")
		(property "Reference" "R245"
			(at 0.799999 -0.4 90)
			(layer "F.SilkS")
			(effects
				(font
					(size 0.7 0.7)
					(thickness 0.15)
				)
				(justify right bottom)
			)
		)
		(property "Value" "R_0R_0402"
			(at -1.011843 1.772047 90)
			(layer "F.Fab")
			(effects
				(font
					(size 0.7 0.7)
					(thickness 0.15)
				)
				(justify right bottom)
			)
		)
		(property "Datasheet" "https://industrial.panasonic.com/cdbs/www-data/pdf/RDA0000/AOA0000C301.pdf"
			(at 0 0 270)
			(layer "F.Fab")
			(hide yes)
			(effects
				(font
					(size 1.27 1.27)
					(thickness 0.15)
				)
			)
		)
		(property "Author" "Antmicro"
			(at 40.64 219.66 0)
			(layer "F.Fab")
			(hide yes)
			(effects
				(font
					(size 1 1)
					(thickness 0.15)
				)
			)
		)
		(property "Current" "1A"
			(at 40.64 219.66 0)
			(layer "F.Fab")
			(hide yes)
			(effects
				(font
					(size 1 1)
					(thickness 0.15)
				)
			)
		)
		(property "License" "Apache-2.0"
			(at 40.64 219.66 0)
			(layer "F.Fab")
			(hide yes)
			(effects
				(font
					(size 1 1)
					(thickness 0.15)
				)
			)
		)
		(property "MPN" "ERJ2GE0R00X"
			(at 40.64 219.66 0)
			(layer "F.Fab")
			(hide yes)
			(effects
				(font
					(size 1 1)
					(thickness 0.15)
				)
			)
		)
		(property "Manufacturer" "Panasonic"
			(at 40.64 219.66 0)
			(layer "F.Fab")
			(hide yes)
			(effects
				(font
					(size 1 1)
					(thickness 0.15)
				)
			)
		)
		(property "Public" "False"
			(at 40.64 219.66 0)
			(layer "F.Fab")
			(hide yes)
			(effects
				(font
					(size 1 1)
					(thickness 0.15)
				)
			)
		)
		(property "Tolerance" ""
			(at 40.64 219.66 0)
			(layer "F.Fab")
			(hide yes)
			(effects
				(font
					(size 1 1)
					(thickness 0.15)
				)
			)
		)
		(property "Val" "0R"
			(at 40.64 219.66 0)
			(layer "F.Fab")
			(hide yes)
			(effects
				(font
					(size 1 1)
					(thickness 0.15)
				)
			)
		)
		(sheetname "GPIO expander")
		(sheetfile "gpio_exp.kicad_sch")
		(attr smd)
		(fp_rect
			(start -0.925 -0.47)
			(end 0.925 0.47)
			(stroke
				(width 0.05)
				(type default)
			)
			(fill no)
			(layer "F.CrtYd")
		)
		(fp_rect
			(start -0.5 -0.25)
			(end 0.5 0.25)
			(stroke
				(width 0.15)
				(type solid)
			)
			(fill no)
			(layer "F.Fab")
		)
		(pad "1" smd roundrect
			(at -0.48 0 270)
			(size 0.59 0.64)
			(layers "F.Cu" "F.Mask" "F.Paste")
			(roundrect_rratio 0.25)
			(net 646 "Net-(U41-IO0_7)")
			(pintype "passive")
			(teardrops
				(best_length_ratio 0.2)
				(max_length 1)
				(best_width_ratio 0.9)
				(max_width 2)
				(curved_edges yes)
				(filter_ratio 0.9)
				(enabled yes)
				(allow_two_segments yes)
				(prefer_zone_connections yes)
			)
		)
		(pad "2" smd roundrect
			(at 0.48 0 270)
			(size 0.59 0.64)
			(layers "F.Cu" "F.Mask" "F.Paste")
			(roundrect_rratio 0.25)
			(net 526 "/Backplane/~{PRSNT}")
			(pintype "passive")
			(teardrops
				(best_length_ratio 0.2)
				(max_length 1)
				(best_width_ratio 0.9)
				(max_width 2)
				(curved_edges yes)
				(filter_ratio 0.9)
				(enabled yes)
				(allow_two_segments yes)
				(prefer_zone_connections yes)
			)
		)
	)
)
